#ISCELL
  pure_quanta quanta_title_block_c *
  *
#CELL
  pure_quanta q_cap *
  page74_i1
#CELL
  pure_quanta q_cap *
  page74_i10
#CELL
  pure_quanta q_cap *
  page74_i11
#CELL
  pure_quanta q_cap *
  page74_i12
#CELL
  pure_quanta q_cap *
  page74_i13
#CELL
  pure_quanta q_cap *
  page74_i14
#CELL
  pure_quanta q_cap *
  page74_i15
#CELL
  pure_quanta q_cap *
  page74_i16
#ISCELL
  pure_quanta_power universal_gnd *
  page74_i17
#CELL
  pure_quanta q_cap *
  page74_i18
#ISCELL
  pure_quanta_power universal_power *
  page74_i2
#ISCELL
  pure_quanta_power universal_power *
  page74_i23
#ISCELL
  pure_quanta_power universal_gnd *
  page74_i24
#CELL
  pure_quanta q_cap *
  page74_i25
#CELL
  pure_quanta q_cap *
  page74_i26
#CELL
  pure_quanta q_cap *
  page74_i3
#ISCELL
  pure_quanta_power universal_power *
  page74_i4
#ISCELL
  pure_quanta_power universal_gnd *
  page74_i7
#CELL
  pure_quanta q_cap *
  page74_i8
#CELL
  pure_quanta q_cap *
  page74_i9
